(kicad_pcb
	(version 20221018)
	(generator pcbnew)
	(general
    (thickness 1.562)
  )
	(paper "A4")
	(title_block
    (title "Thunderbolt PCIe Adaper")
    (date "2024-07-09")
    (rev "1.0.3")
    (comment 1 "www.antmicro.com")
    (comment 2 "Antmicro Ltd.")
		(comment 9 "footprints 80-88 of 271")
	)
	(layers
    (0 "F.Cu" signal)
    (1 "In1.Cu" signal)
    (2 "In2.Cu" signal)
    (3 "In3.Cu" signal)
    (4 "In4.Cu" signal)
    (31 "B.Cu" signal)
    (32 "B.Adhes" user "B.Adhesive")
    (33 "F.Adhes" user "F.Adhesive")
    (34 "B.Paste" user)
    (35 "F.Paste" user)
    (36 "B.SilkS" user "B.Silkscreen")
    (37 "F.SilkS" user "F.Silkscreen")
    (38 "B.Mask" user)
    (39 "F.Mask" user)
    (40 "Dwgs.User" user "User.Drawings")
    (41 "Cmts.User" user "User.Comments")
    (42 "Eco1.User" user "User.Eco1")
    (43 "Eco2.User" user "User.Eco2")
    (44 "Edge.Cuts" user)
    (45 "Margin" user)
    (46 "B.CrtYd" user "B.Courtyard")
    (47 "F.CrtYd" user "F.Courtyard")
    (48 "B.Fab" user)
    (49 "F.Fab" user)
  )
	(footprint "antmicro-footprints:C_0402_1005Metric" (layer "B.Cu")
    (at 144.30859 90.885531 -135)
    (descr "Capacitor SMD 0402")
    (tags "capacitor SMD 0402")
    (property "Author" "Antmicro")
    (property "Dielectric" "C0G")
    (property "License" "Apache-2.0")
    (property "MPN" "GCM1555C1H100GA16D")
    (property "Manufacturer" "Murata")
    (property "Sheetfile" "tb.kicad_sch")
    (property "Sheetname" "TB Controller")
    (property "Val" "10p")
    (property "Voltage" "50V")
    (property "ki_description" "SMD Multilayer Ceramic Capacitor, 10 pF, 50 V, 0402 [1005 Metric], ± 2%, C0G / NP0, GCM")
    (property "ki_keywords" "0402, SMT, CAPACITOR, PASSIVE")
    (attr smd)
    (fp_text reference "C116" (at -1.018899 -1.443826 45) (layer "B.SilkS")
        (effects (font (size 0.7 0.7) (thickness 0.15)) (justify left bottom mirror))
    )
    (fp_text value "C_10p_0402" (at -1.022927 -2.155213 45) (layer "B.Fab")
        (effects (font (size 0.7 0.7) (thickness 0.15)) (justify left bottom mirror))
    )
    (fp_text user "${REFERENCE}" (at -0.939 -4.599 45) (layer "B.Fab") hide
        (effects (font (size 0.7 0.7) (thickness 0.15)) (justify left bottom mirror))
    )
    (fp_text user "Author: Antmicro" (at -0.939 -3.399 45) (layer "B.Fab") hide
        (effects (font (size 0.7 0.7) (thickness 0.15)) (justify left bottom mirror))
    )
    (fp_text user "License: Apache-2.0" (at -0.939 -5.799 45) (layer "B.Fab") hide
        (effects (font (size 0.7 0.7) (thickness 0.15)) (justify left bottom mirror))
    )
    (fp_rect (start -0.925 0.47) (end 0.925 -0.47)
      (stroke (width 0.05) (type default)) (fill none) (layer "B.CrtYd"))
    (fp_line (start -0.494 -0.248) (end -0.494 0.25)
      (stroke (width 0.15) (type solid)) (layer "B.Fab"))
    (fp_line (start -0.494 0.25) (end 0.504 0.25)
      (stroke (width 0.15) (type solid)) (layer "B.Fab"))
    (fp_line (start 0.504 -0.248) (end -0.494 -0.248)
      (stroke (width 0.15) (type solid)) (layer "B.Fab"))
    (fp_line (start 0.504 0.25) (end 0.504 -0.248)
      (stroke (width 0.15) (type solid)) (layer "B.Fab"))
    (pad "1" smd roundrect (at -0.48 0 225) (size 0.59 0.64) (layers "B.Cu" "B.Paste" "B.Mask") (roundrect_rratio 0.25)
      (net 117 "Net-(U4D-XTAL_25_IN)") (pintype "passive"))
    (pad "2" smd roundrect (at 0.48 0 225) (size 0.59 0.64) (layers "B.Cu" "B.Paste" "B.Mask") (roundrect_rratio 0.25)
      (net 1 "GND") (pintype "passive"))
  )
	(footprint "antmicro-footprints:C_0402_1005Metric" (layer "B.Cu")
    (at 134.925 81.8 180)
    (descr "Capacitor SMD 0402")
    (tags "capacitor SMD 0402")
    (property "Author" "Antmicro")
    (property "Dielectric" "")
    (property "License" "Apache-2.0")
    (property "MPN" "C1005X6S1A105K050BC")
    (property "Manufacturer" "TDK")
    (property "Sheetfile" "tb-power.kicad_sch")
    (property "Sheetname" "Thunderbolt Controller - Power")
    (property "Val" "1u")
    (property "Voltage" "")
    (property "ki_description" "SMD Multilayer Ceramic Capacitor, 1 µF, 10 V, 0402 [1005 Metric], ± 10%, X6S, C")
    (property "ki_keywords" "0402, SMT, CAPACITOR, PASSIVE, CERAMIC, MLCC")
    (attr smd)
    (fp_text reference "C59" (at -17.475 -7.735) (layer "B.SilkS")
        (effects (font (size 0.7 0.7) (thickness 0.15)) (justify left bottom mirror))
    )
    (fp_text value "C_1u_0402" (at -1.022927 -2.155213) (layer "B.Fab")
        (effects (font (size 0.7 0.7) (thickness 0.15)) (justify left bottom mirror))
    )
    (fp_text user "Author: Antmicro" (at -0.939 -3.399) (layer "B.Fab") hide
        (effects (font (size 0.7 0.7) (thickness 0.15)) (justify left bottom mirror))
    )
    (fp_text user "License: Apache-2.0" (at -0.939 -5.799) (layer "B.Fab") hide
        (effects (font (size 0.7 0.7) (thickness 0.15)) (justify left bottom mirror))
    )
    (fp_text user "${REFERENCE}" (at -0.939 -4.599) (layer "B.Fab") hide
        (effects (font (size 0.7 0.7) (thickness 0.15)) (justify left bottom mirror))
    )
    (fp_rect (start -0.925 0.47) (end 0.925 -0.47)
      (stroke (width 0.05) (type default)) (fill none) (layer "B.CrtYd"))
    (fp_line (start -0.494 -0.248) (end -0.494 0.25)
      (stroke (width 0.15) (type solid)) (layer "B.Fab"))
    (fp_line (start -0.494 0.25) (end 0.504 0.25)
      (stroke (width 0.15) (type solid)) (layer "B.Fab"))
    (fp_line (start 0.504 -0.248) (end -0.494 -0.248)
      (stroke (width 0.15) (type solid)) (layer "B.Fab"))
    (fp_line (start 0.504 0.25) (end 0.504 -0.248)
      (stroke (width 0.15) (type solid)) (layer "B.Fab"))
    (pad "1" smd roundrect (at -0.48 0 180) (size 0.59 0.64) (layers "B.Cu" "B.Paste" "B.Mask") (roundrect_rratio 0.25)
      (net 1 "GND") (pintype "passive"))
    (pad "2" smd roundrect (at 0.48 0 180) (size 0.59 0.64) (layers "B.Cu" "B.Paste" "B.Mask") (roundrect_rratio 0.25)
      (net 108 "Net-(C56-Pad2)") (pintype "passive"))
  )
	(footprint "antmicro-footprints:C_0402_1005Metric" (layer "B.Cu")
    (at 135.115 59.1 180)
    (descr "Capacitor SMD 0402")
    (tags "capacitor SMD 0402")
    (property "Author" "Antmicro")
    (property "Dielectric" "X5R")
    (property "License" "Apache-2.0")
    (property "MPN" "GRM155R61H104KE14D")
    (property "Manufacturer" "Murata")
    (property "Sheetfile" "tb.kicad_sch")
    (property "Sheetname" "TB Controller")
    (property "Val" "100n")
    (property "Voltage" "50V")
    (property "ki_description" "SMD Multilayer Ceramic Capacitor, 0.1 µF, 50 V, 0402 [1005 Metric], ± 10%, X5R, GRM Series")
    (property "ki_keywords" "0402, SMT, CAPACITOR, PASSIVE, CERAMIC, MLCC")
    (attr smd)
    (fp_text reference "C104" (at 1.003 -0.463) (layer "B.SilkS")
        (effects (font (size 0.7 0.7) (thickness 0.15)) (justify left bottom mirror))
    )
    (fp_text value "C_100n_0402" (at -1.022927 -2.155213) (layer "B.Fab")
        (effects (font (size 0.7 0.7) (thickness 0.15)) (justify left bottom mirror))
    )
    (fp_text user "${REFERENCE}" (at -0.939 -4.599) (layer "B.Fab") hide
        (effects (font (size 0.7 0.7) (thickness 0.15)) (justify left bottom mirror))
    )
    (fp_text user "License: Apache-2.0" (at -0.939 -5.799) (layer "B.Fab") hide
        (effects (font (size 0.7 0.7) (thickness 0.15)) (justify left bottom mirror))
    )
    (fp_text user "Author: Antmicro" (at -0.939 -3.399) (layer "B.Fab") hide
        (effects (font (size 0.7 0.7) (thickness 0.15)) (justify left bottom mirror))
    )
    (fp_rect (start -0.925 0.47) (end 0.925 -0.47)
      (stroke (width 0.05) (type default)) (fill none) (layer "B.CrtYd"))
    (fp_line (start -0.494 -0.248) (end -0.494 0.25)
      (stroke (width 0.15) (type solid)) (layer "B.Fab"))
    (fp_line (start -0.494 0.25) (end 0.504 0.25)
      (stroke (width 0.15) (type solid)) (layer "B.Fab"))
    (fp_line (start 0.504 -0.248) (end -0.494 -0.248)
      (stroke (width 0.15) (type solid)) (layer "B.Fab"))
    (fp_line (start 0.504 0.25) (end 0.504 -0.248)
      (stroke (width 0.15) (type solid)) (layer "B.Fab"))
    (pad "1" smd roundrect (at -0.48 0 180) (size 0.59 0.64) (layers "B.Cu" "B.Paste" "B.Mask") (roundrect_rratio 0.25)
      (net 23 "AUX_N") (pintype "passive"))
    (pad "2" smd roundrect (at 0.48 0 180) (size 0.59 0.64) (layers "B.Cu" "B.Paste" "B.Mask") (roundrect_rratio 0.25)
      (net 87 "/TB Controller/PA_AUX_N") (pintype "passive"))
  )
	(footprint "antmicro-footprints:R_0402_1005Metric" (layer "B.Cu")
    (at 114.145 86.17 -90)
    (descr "Resistor SMD 0402")
    (tags "resistor SMD 0402")
    (property "Author" "Antmicro")
    (property "License" "Apache-2.0")
    (property "MPN" "CR0402-FX-1103GLF")
    (property "Manufacturer" "Bourns")
    (property "Sheetfile" "power.kicad_sch")
    (property "Sheetname" "Power")
    (property "Tolerance" "1%")
    (property "Val" "110k")
    (property "ki_description" "SMD Chip Resistor, 110 kohm, ± 1%, 63 mW, 0402 [1005 Metric], Thick Film, General Purpose")
    (property "ki_keywords" "0402, SMT, RESISTOR, PASSIVE")
    (attr smd)
    (fp_text reference "R43" (at 0.825 -0.409 90) (layer "B.SilkS")
        (effects (font (size 0.7 0.7) (thickness 0.15)) (justify left bottom mirror))
    )
    (fp_text value "R_110k_0402" (at -1.011843 -1.772047 90) (layer "B.Fab")
        (effects (font (size 0.7 0.7) (thickness 0.15)) (justify left bottom mirror))
    )
    (fp_text user "License: Apache-2.0" (at -0.95 -5.169 90) (layer "B.Fab") hide
        (effects (font (size 0.7 0.7) (thickness 0.15)) (justify left bottom mirror))
    )
    (fp_text user "Author: Antmicro" (at -0.95 -4.169 90) (layer "B.Fab") hide
        (effects (font (size 0.7 0.7) (thickness 0.15)) (justify left bottom mirror))
    )
    (fp_text user "${REFERENCE}" (at -0.95 -3.168 90) (layer "B.Fab") hide
        (effects (font (size 0.7 0.7) (thickness 0.15)) (justify left bottom mirror))
    )
    (fp_rect (start -0.925 0.47) (end 0.925 -0.47)
      (stroke (width 0.05) (type default)) (fill none) (layer "B.CrtYd"))
    (fp_rect (start -0.5 0.25) (end 0.5 -0.25)
      (stroke (width 0.15) (type solid)) (fill none) (layer "B.Fab"))
    (pad "1" smd roundrect (at -0.48 0 270) (size 0.59 0.64) (layers "B.Cu" "B.Paste" "B.Mask") (roundrect_rratio 0.25)
      (net 169 "Net-(U1-FB)") (pintype "passive"))
    (pad "2" smd roundrect (at 0.48 0 270) (size 0.59 0.64) (layers "B.Cu" "B.Paste" "B.Mask") (roundrect_rratio 0.25)
      (net 75 "Net-(C32-Pad2)") (pintype "passive"))
  )
	(footprint "antmicro-footprints:R_0402_1005Metric" (layer "B.Cu")
    (at 152.91 60.47 90)
    (descr "Resistor SMD 0402")
    (tags "resistor SMD 0402")
    (property "Author" "Antmicro")
    (property "License" "Apache-2.0")
    (property "MPN" "CR0402-FX-1002GLF")
    (property "Manufacturer" "Bourns")
    (property "Sheetfile" "power.kicad_sch")
    (property "Sheetname" "Power")
    (property "Tolerance" "1%")
    (property "Val" "10k")
    (property "ki_description" "SMD Chip Resistor, 10 kohm, ± 1%, 62.5 mW, 0402 [1005 Metric], Thick Film, General Purpose")
    (property "ki_keywords" "0402, SMT, RESISTOR, PASSIVE")
    (attr smd)
    (fp_text reference "R17" (at 3.193 0.379 270) (layer "B.SilkS")
        (effects (font (size 0.7 0.7) (thickness 0.15)) (justify left bottom mirror))
    )
    (fp_text value "R_10k_0402" (at -1.011843 -1.772047 270) (layer "B.Fab")
        (effects (font (size 0.7 0.7) (thickness 0.15)) (justify left bottom mirror))
    )
    (fp_text user "Author: Antmicro" (at -0.95 -4.169 270) (layer "B.Fab") hide
        (effects (font (size 0.7 0.7) (thickness 0.15)) (justify left bottom mirror))
    )
    (fp_text user "License: Apache-2.0" (at -0.95 -5.169 270) (layer "B.Fab") hide
        (effects (font (size 0.7 0.7) (thickness 0.15)) (justify left bottom mirror))
    )
    (fp_text user "${REFERENCE}" (at -0.95 -3.168 270) (layer "B.Fab") hide
        (effects (font (size 0.7 0.7) (thickness 0.15)) (justify left bottom mirror))
    )
    (fp_rect (start -0.925 0.47) (end 0.925 -0.47)
      (stroke (width 0.05) (type default)) (fill none) (layer "B.CrtYd"))
    (fp_rect (start -0.5 0.25) (end 0.5 -0.25)
      (stroke (width 0.15) (type solid)) (fill none) (layer "B.Fab"))
    (pad "1" smd roundrect (at -0.48 0 90) (size 0.59 0.64) (layers "B.Cu" "B.Paste" "B.Mask") (roundrect_rratio 0.25)
      (net 9 "/Power/TPS_3V3") (pintype "passive"))
    (pad "2" smd roundrect (at 0.48 0 90) (size 0.59 0.64) (layers "B.Cu" "B.Paste" "B.Mask") (roundrect_rratio 0.25)
      (net 152 "Net-(U3-GPIO0(HD3_AMSEL))") (pintype "passive"))
  )
	(footprint "antmicro-footprints:R_0402_1005Metric" (layer "B.Cu")
    (at 135.175 68.77 90)
    (descr "Resistor SMD 0402")
    (tags "resistor SMD 0402")
    (property "Author" "Antmicro")
    (property "License" "Apache-2.0")
    (property "MPN" "CR0402-FX-1003GLF")
    (property "Manufacturer" "Bourns")
    (property "Sheetfile" "tb.kicad_sch")
    (property "Sheetname" "TB Controller")
    (property "Tolerance" "1%")
    (property "Val" "100k")
    (property "ki_description" "SMD Chip Resistor, 100 kohm, ± 1%, 62.5 mW, 0402 [1005 Metric], Thick Film, General Purpose")
    (property "ki_keywords" "0402, SMT, RESISTOR, PASSIVE")
    (attr smd)
    (fp_text reference "R75" (at 1.124 3.736 270) (layer "B.SilkS")
        (effects (font (size 0.7 0.7) (thickness 0.15)) (justify left bottom mirror))
    )
    (fp_text value "R_100k_0402" (at -1.011843 -1.772047 270) (layer "B.Fab")
        (effects (font (size 0.7 0.7) (thickness 0.15)) (justify left bottom mirror))
    )
    (fp_text user "License: Apache-2.0" (at -0.95 -5.169 270) (layer "B.Fab") hide
        (effects (font (size 0.7 0.7) (thickness 0.15)) (justify left bottom mirror))
    )
    (fp_text user "${REFERENCE}" (at -0.95 -3.168 270) (layer "B.Fab") hide
        (effects (font (size 0.7 0.7) (thickness 0.15)) (justify left bottom mirror))
    )
    (fp_text user "Author: Antmicro" (at -0.95 -4.169 270) (layer "B.Fab") hide
        (effects (font (size 0.7 0.7) (thickness 0.15)) (justify left bottom mirror))
    )
    (fp_rect (start -0.925 0.47) (end 0.925 -0.47)
      (stroke (width 0.05) (type default)) (fill none) (layer "B.CrtYd"))
    (fp_rect (start -0.5 0.25) (end 0.5 -0.25)
      (stroke (width 0.15) (type solid)) (fill none) (layer "B.Fab"))
    (pad "1" smd roundrect (at -0.48 0 90) (size 0.59 0.64) (layers "B.Cu" "B.Paste" "B.Mask") (roundrect_rratio 0.25)
      (net 190 "Net-(U4C-DPSRC_HPD)") (pintype "passive"))
    (pad "2" smd roundrect (at 0.48 0 90) (size 0.59 0.64) (layers "B.Cu" "B.Paste" "B.Mask") (roundrect_rratio 0.25)
      (net 1 "GND") (pintype "passive"))
  )
	(footprint "antmicro-footprints:C_0402_1005Metric" (layer "B.Cu")
    (at 141.15 76.43 90)
    (descr "Capacitor SMD 0402")
    (tags "capacitor SMD 0402")
    (property "Author" "Antmicro")
    (property "Dielectric" "X5R")
    (property "License" "Apache-2.0")
    (property "MPN" "GRM155R61H104KE14D")
    (property "Manufacturer" "Murata")
    (property "Sheetfile" "tb-power.kicad_sch")
    (property "Sheetname" "Thunderbolt Controller - Power")
    (property "Val" "100n")
    (property "Voltage" "50V")
    (property "ki_description" "SMD Multilayer Ceramic Capacitor, 0.1 µF, 50 V, 0402 [1005 Metric], ± 10%, X5R, GRM Series")
    (property "ki_keywords" "0402, SMT, CAPACITOR, PASSIVE, CERAMIC, MLCC")
    (attr smd)
    (fp_text reference "C88" (at 5.437 1.471 270) (layer "B.SilkS")
        (effects (font (size 0.7 0.7) (thickness 0.15)) (justify left bottom mirror))
    )
    (fp_text value "C_100n_0402" (at -1.022927 -2.155213 270) (layer "B.Fab")
        (effects (font (size 0.7 0.7) (thickness 0.15)) (justify left bottom mirror))
    )
    (fp_text user "${REFERENCE}" (at -0.939 -4.599 270) (layer "B.Fab") hide
        (effects (font (size 0.7 0.7) (thickness 0.15)) (justify left bottom mirror))
    )
    (fp_text user "License: Apache-2.0" (at -0.939 -5.799 270) (layer "B.Fab") hide
        (effects (font (size 0.7 0.7) (thickness 0.15)) (justify left bottom mirror))
    )
    (fp_text user "Author: Antmicro" (at -0.939 -3.399 270) (layer "B.Fab") hide
        (effects (font (size 0.7 0.7) (thickness 0.15)) (justify left bottom mirror))
    )
    (fp_rect (start -0.925 0.47) (end 0.925 -0.47)
      (stroke (width 0.05) (type default)) (fill none) (layer "B.CrtYd"))
    (fp_line (start -0.494 -0.248) (end -0.494 0.25)
      (stroke (width 0.15) (type solid)) (layer "B.Fab"))
    (fp_line (start -0.494 0.25) (end 0.504 0.25)
      (stroke (width 0.15) (type solid)) (layer "B.Fab"))
    (fp_line (start 0.504 -0.248) (end -0.494 -0.248)
      (stroke (width 0.15) (type solid)) (layer "B.Fab"))
    (fp_line (start 0.504 0.25) (end 0.504 -0.248)
      (stroke (width 0.15) (type solid)) (layer "B.Fab"))
    (pad "1" smd roundrect (at -0.48 0 90) (size 0.59 0.64) (layers "B.Cu" "B.Paste" "B.Mask") (roundrect_rratio 0.25)
      (net 1 "GND") (pintype "passive"))
    (pad "2" smd roundrect (at 0.48 0 90) (size 0.59 0.64) (layers "B.Cu" "B.Paste" "B.Mask") (roundrect_rratio 0.25)
      (net 2 "3V3_SYS") (pintype "passive"))
  )
	(footprint "antmicro-footprints:R_0402_1005Metric" (layer "B.Cu")
    (at 126.25 62.75)
    (descr "Resistor SMD 0402")
    (tags "resistor SMD 0402")
    (property "Author" "Antmicro")
    (property "License" "Apache-2.0")
    (property "MPN" "CR0402-FX-3300GLF")
    (property "Manufacturer" "Bourns")
    (property "Sheetfile" "power.kicad_sch")
    (property "Sheetname" "Power")
    (property "Tolerance" "1%")
    (property "Val" "330R")
    (property "ki_description" "SMD Chip Resistor, 330 ohm, ± 1%, 62.5 mW, 0402 [1005 Metric], Thick Film, General Purpose")
    (property "ki_keywords" "0402, SMT, RESISTOR, PASSIVE")
    (attr smd)
    (fp_text reference "R42" (at 1.131 -0.647 180) (layer "B.SilkS")
        (effects (font (size 0.7 0.7) (thickness 0.15)) (justify left bottom mirror))
    )
    (fp_text value "R_330R_0402" (at -1.011843 -1.772047 180) (layer "B.Fab")
        (effects (font (size 0.7 0.7) (thickness 0.15)) (justify left bottom mirror))
    )
    (fp_text user "License: Apache-2.0" (at -0.95 -5.169 180) (layer "B.Fab") hide
        (effects (font (size 0.7 0.7) (thickness 0.15)) (justify left bottom mirror))
    )
    (fp_text user "${REFERENCE}" (at -0.95 -3.168 180) (layer "B.Fab") hide
        (effects (font (size 0.7 0.7) (thickness 0.15)) (justify left bottom mirror))
    )
    (fp_text user "Author: Antmicro" (at -0.95 -4.169 180) (layer "B.Fab") hide
        (effects (font (size 0.7 0.7) (thickness 0.15)) (justify left bottom mirror))
    )
    (fp_rect (start -0.925 0.47) (end 0.925 -0.47)
      (stroke (width 0.05) (type default)) (fill none) (layer "B.CrtYd"))
    (fp_rect (start -0.5 0.25) (end 0.5 -0.25)
      (stroke (width 0.15) (type solid)) (fill none) (layer "B.Fab"))
    (pad "1" smd roundrect (at -0.48 0) (size 0.59 0.64) (layers "B.Cu" "B.Paste" "B.Mask") (roundrect_rratio 0.25)
      (net 1 "GND") (pintype "passive"))
    (pad "2" smd roundrect (at 0.48 0) (size 0.59 0.64) (layers "B.Cu" "B.Paste" "B.Mask") (roundrect_rratio 0.25)
      (net 120 "Net-(D2-C)") (pintype "passive"))
  )
	(footprint "antmicro-footprints:C_0402_1005Metric" (layer "B.Cu")
    (at 108.915 80.65 180)
    (descr "Capacitor SMD 0402")
    (tags "capacitor SMD 0402")
    (property "Author" "Antmicro")
    (property "Dielectric" "X5R")
    (property "License" "Apache-2.0")
    (property "MPN" "GRM155R61H104KE14D")
    (property "Manufacturer" "Murata")
    (property "Sheetfile" "power.kicad_sch")
    (property "Sheetname" "Power")
    (property "Val" "100n")
    (property "Voltage" "50V")
    (property "ki_description" "SMD Multilayer Ceramic Capacitor, 0.1 µF, 50 V, 0402 [1005 Metric], ± 10%, X5R, GRM Series")
    (property "ki_keywords" "0402, SMT, CAPACITOR, PASSIVE, CERAMIC, MLCC")
    (attr smd)
    (fp_text reference "C14" (at -1.067 5.72) (layer "B.SilkS")
        (effects (font (size 0.7 0.7) (thickness 0.15)) (justify left bottom mirror))
    )
    (fp_text value "C_100n_0402" (at -1.022927 -2.155213) (layer "B.Fab")
        (effects (font (size 0.7 0.7) (thickness 0.15)) (justify left bottom mirror))
    )
    (fp_text user "${REFERENCE}" (at -0.939 -4.599) (layer "B.Fab") hide
        (effects (font (size 0.7 0.7) (thickness 0.15)) (justify left bottom mirror))
    )
    (fp_text user "License: Apache-2.0" (at -0.939 -5.799) (layer "B.Fab") hide
        (effects (font (size 0.7 0.7) (thickness 0.15)) (justify left bottom mirror))
    )
    (fp_text user "Author: Antmicro" (at -0.939 -3.399) (layer "B.Fab") hide
        (effects (font (size 0.7 0.7) (thickness 0.15)) (justify left bottom mirror))
    )
    (fp_rect (start -0.925 0.47) (end 0.925 -0.47)
      (stroke (width 0.05) (type default)) (fill none) (layer "B.CrtYd"))
    (fp_line (start -0.494 -0.248) (end -0.494 0.25)
      (stroke (width 0.15) (type solid)) (layer "B.Fab"))
    (fp_line (start -0.494 0.25) (end 0.504 0.25)
      (stroke (width 0.15) (type solid)) (layer "B.Fab"))
    (fp_line (start 0.504 -0.248) (end -0.494 -0.248)
      (stroke (width 0.15) (type solid)) (layer "B.Fab"))
    (fp_line (start 0.504 0.25) (end 0.504 -0.248)
      (stroke (width 0.15) (type solid)) (layer "B.Fab"))
    (pad "1" smd roundrect (at -0.48 0 180) (size 0.59 0.64) (layers "B.Cu" "B.Paste" "B.Mask") (roundrect_rratio 0.25)
      (net 1 "GND") (pintype "passive"))
    (pad "2" smd roundrect (at 0.48 0 180) (size 0.59 0.64) (layers "B.Cu" "B.Paste" "B.Mask") (roundrect_rratio 0.25)
      (net 74 "Net-(C10-Pad2)") (pintype "passive"))
  )
)
